(kicad_pcb
	(version 20260206)
	(generator "pcbnew")
	(generator_version "10.0")
	(general
		(thickness 1.6)
		(legacy_teardrops no)
	)
	(paper "A4")
	(title_block
		(title "01162023_DA0F0TEBIF0_F0T_Expander_BD_F_brd_V02_OCP.brd")
		(comment 1 "Grand Teton / footprints 5884-5891 of 9728")
	)
	(layers
		(0 "F.Cu" signal "TOP")
		(4 "In1.Cu" signal "GND")
		(6 "In2.Cu" signal "VCC")
		(8 "In3.Cu" signal "VCC1")
		(10 "In4.Cu" signal "GND1")
		(12 "In5.Cu" signal "IN1")
		(14 "In6.Cu" signal "GND2")
		(16 "In7.Cu" signal "IN2")
		(18 "In8.Cu" signal "GND3")
		(20 "In9.Cu" signal "IN3")
		(22 "In10.Cu" signal "GND4")
		(24 "In11.Cu" signal "IN4")
		(26 "In12.Cu" signal "GND5")
		(28 "In13.Cu" signal "IN5")
		(30 "In14.Cu" signal "GND6")
		(32 "In15.Cu" signal "IN6")
		(34 "In16.Cu" signal "GND7")
		(2 "B.Cu" signal "BOTTOM")
		(9 "F.Adhes" user "F.Adhesive")
		(11 "B.Adhes" user "B.Adhesive")
		(13 "F.Paste" user "Package Geometry/Pastemask Top")
		(15 "B.Paste" user "Package Geometry/Pastemask Bottom")
		(5 "F.SilkS" user "Ref Des/Silkscreen Top")
		(7 "B.SilkS" user "Ref Des/Silkscreen Bottom")
		(1 "F.Mask" user "Board Geometry/Soldermask Top")
		(3 "B.Mask" user "Board Geometry/Soldermask Bottom")
		(17 "Dwgs.User" user "User.Drawings")
		(19 "Cmts.User" user "User.Comments")
		(21 "Eco1.User" user "User.Eco1")
		(23 "Eco2.User" user "User.Eco2")
		(25 "Edge.Cuts" user "Board Geometry/Outline")
		(27 "Margin" user)
		(31 "F.CrtYd" user "Package Geometry/Place Bound Top")
		(29 "B.CrtYd" user "Package Geometry/Place Bound Bottom")
		(35 "F.Fab" user "Ref Des/Assembly Top")
		(33 "B.Fab" user "Ref Des/Assembly Bottom")
	)
	(footprint ""
		(layer "F.Cu")
		(at 133.93039 -184.656984 -90)
		(property "Reference" "R1113"
			(at 0 0 270)
			(layer "F.SilkS")
			(hide yes)
			(effects
				(font
					(size 1.27 1.27)
				)
			)
		)
		(property "Value" ""
			(at 0 0 270)
			(layer "F.Fab")
			(effects
				(font
					(size 1.27 1.27)
				)
			)
		)
		(duplicate_pad_numbers_are_jumpers no)
		(fp_line
			(start 0.7874 0.4064)
			(end -0.7874 0.4064)
			(stroke
				(width 0.1524)
				(type default)
			)
			(layer "F.SilkS")
		)
		(fp_line
			(start -0.67945 0.3048)
			(end -0.67945 -0.305054)
			(stroke
				(width 0.1)
				(type default)
			)
			(layer "F.Fab")
		)
		(fp_line
			(start -0.12065 0.3048)
			(end -0.67945 0.3048)
			(stroke
				(width 0.1)
				(type default)
			)
			(layer "F.Fab")
		)
		(fp_line
			(start 0.120396 0.3048)
			(end 0.120396 0.2794)
			(stroke
				(width 0.1)
				(type default)
			)
			(layer "F.Fab")
		)
		(fp_line
			(start 0.67945 0.3048)
			(end 0.120396 0.3048)
			(stroke
				(width 0.1)
				(type default)
			)
			(layer "F.Fab")
		)
		(fp_line
			(start -0.12065 0.2794)
			(end -0.12065 0.3048)
			(stroke
				(width 0.1)
				(type default)
			)
			(layer "F.Fab")
		)
		(fp_line
			(start 0.120396 0.2794)
			(end -0.12065 0.2794)
			(stroke
				(width 0.1)
				(type default)
			)
			(layer "F.Fab")
		)
		(fp_line
			(start -0.12065 -0.2794)
			(end 0.12065 -0.2794)
			(stroke
				(width 0.1)
				(type default)
			)
			(layer "F.Fab")
		)
		(fp_line
			(start 0.12065 -0.2794)
			(end 0.12065 -0.3048)
			(stroke
				(width 0.1)
				(type default)
			)
			(layer "F.Fab")
		)
		(fp_line
			(start 0.12065 -0.3048)
			(end 0.67945 -0.3048)
			(stroke
				(width 0.1)
				(type default)
			)
			(layer "F.Fab")
		)
		(fp_line
			(start 0.67945 -0.3048)
			(end 0.67945 0.3048)
			(stroke
				(width 0.1)
				(type default)
			)
			(layer "F.Fab")
		)
		(fp_line
			(start -0.67945 -0.305054)
			(end -0.12065 -0.305054)
			(stroke
				(width 0.1)
				(type default)
			)
			(layer "F.Fab")
		)
		(fp_line
			(start -0.12065 -0.305054)
			(end -0.12065 -0.2794)
			(stroke
				(width 0.1)
				(type default)
			)
			(layer "F.Fab")
		)
		(pad "1" smd circle
			(at -0.40005 0 270)
			(size 0 0)
			(layers "F.Cu" "F.Mask" "F.Paste")
			(net "CLK_100M_DB2000QL_GPU_REF0_R_DN")
		)
		(pad "2" smd circle
			(at 0.40005 0 270)
			(size 0 0)
			(layers "F.Cu" "F.Mask" "F.Paste")
			(net "CLK_100M_DB2000QL_GPU_REF0_DN")
		)
	)
	(footprint ""
		(layer "F.Cu")
		(at 250.147074 -55.63489 90)
		(property "Reference" "PC861"
			(at 0 0 90)
			(layer "F.SilkS")
			(hide yes)
			(effects
				(font
					(size 1.27 1.27)
				)
			)
		)
		(property "Value" ""
			(at 0 0 90)
			(layer "F.Fab")
			(effects
				(font
					(size 1.27 1.27)
				)
			)
		)
		(duplicate_pad_numbers_are_jumpers no)
		(fp_line
			(start 1.524 -0.762)
			(end 1.524 0.762)
			(stroke
				(width 0.1524)
				(type default)
			)
			(layer "F.SilkS")
		)
		(fp_line
			(start -1.524 -0.762)
			(end 1.524 -0.762)
			(stroke
				(width 0.1524)
				(type default)
			)
			(layer "F.SilkS")
		)
		(fp_line
			(start 1.524 0.762)
			(end -1.524 0.762)
			(stroke
				(width 0.1524)
				(type default)
			)
			(layer "F.SilkS")
		)
		(fp_line
			(start -1.524 0.762)
			(end -1.524 -0.762)
			(stroke
				(width 0.1524)
				(type default)
			)
			(layer "F.SilkS")
		)
		(fp_line
			(start 1.1049 -0.724916)
			(end -1.1049 -0.724916)
			(stroke
				(width 0.1)
				(type default)
			)
			(layer "F.Fab")
		)
		(fp_line
			(start -1.1049 -0.724916)
			(end -1.1049 0.724916)
			(stroke
				(width 0.1)
				(type default)
			)
			(layer "F.Fab")
		)
		(fp_line
			(start 1.1049 0.724916)
			(end 1.1049 -0.724916)
			(stroke
				(width 0.1)
				(type default)
			)
			(layer "F.Fab")
		)
		(fp_line
			(start -1.1049 0.724916)
			(end 1.1049 0.724916)
			(stroke
				(width 0.1)
				(type default)
			)
			(layer "F.Fab")
		)
		(pad "1" smd rect
			(at -0.889 0 270)
			(size 1.016 1.27)
			(layers "F.Cu" "F.Mask" "F.Paste")
			(net "P12V_SSD8_R")
		)
		(pad "2" smd rect
			(at 0.889 0 270)
			(size 1.016 1.27)
			(layers "F.Cu" "F.Mask" "F.Paste")
			(net "GND")
		)
	)
	(footprint ""
		(layer "F.Cu")
		(at 154.699716 -152.295352 180)
		(property "Reference" "R119"
			(at 0 0 180)
			(layer "F.SilkS")
			(hide yes)
			(effects
				(font
					(size 1.27 1.27)
				)
			)
		)
		(property "Value" ""
			(at 0 0 180)
			(layer "F.Fab")
			(effects
				(font
					(size 1.27 1.27)
				)
			)
		)
		(duplicate_pad_numbers_are_jumpers no)
		(fp_line
			(start 0.7874 0.4064)
			(end -0.7874 0.4064)
			(stroke
				(width 0.1524)
				(type default)
			)
			(layer "F.SilkS")
		)
		(fp_line
			(start 0.7874 -0.4064)
			(end 0.7874 0.4064)
			(stroke
				(width 0.1524)
				(type default)
			)
			(layer "F.SilkS")
		)
		(fp_line
			(start -0.7874 0.4064)
			(end -0.7874 -0.4064)
			(stroke
				(width 0.1524)
				(type default)
			)
			(layer "F.SilkS")
		)
		(fp_line
			(start -0.7874 -0.4064)
			(end 0.7874 -0.4064)
			(stroke
				(width 0.1524)
				(type default)
			)
			(layer "F.SilkS")
		)
		(fp_line
			(start 0.67945 0.3048)
			(end 0.120396 0.3048)
			(stroke
				(width 0.1)
				(type default)
			)
			(layer "F.Fab")
		)
		(fp_line
			(start 0.67945 -0.3048)
			(end 0.67945 0.3048)
			(stroke
				(width 0.1)
				(type default)
			)
			(layer "F.Fab")
		)
		(fp_line
			(start 0.12065 -0.2794)
			(end 0.12065 -0.3048)
			(stroke
				(width 0.1)
				(type default)
			)
			(layer "F.Fab")
		)
		(fp_line
			(start 0.12065 -0.3048)
			(end 0.67945 -0.3048)
			(stroke
				(width 0.1)
				(type default)
			)
			(layer "F.Fab")
		)
		(fp_line
			(start 0.120396 0.3048)
			(end 0.120396 0.2794)
			(stroke
				(width 0.1)
				(type default)
			)
			(layer "F.Fab")
		)
		(fp_line
			(start 0.120396 0.2794)
			(end -0.12065 0.2794)
			(stroke
				(width 0.1)
				(type default)
			)
			(layer "F.Fab")
		)
		(fp_line
			(start -0.12065 0.3048)
			(end -0.67945 0.3048)
			(stroke
				(width 0.1)
				(type default)
			)
			(layer "F.Fab")
		)
		(fp_line
			(start -0.12065 0.2794)
			(end -0.12065 0.3048)
			(stroke
				(width 0.1)
				(type default)
			)
			(layer "F.Fab")
		)
		(fp_line
			(start -0.12065 -0.2794)
			(end 0.12065 -0.2794)
			(stroke
				(width 0.1)
				(type default)
			)
			(layer "F.Fab")
		)
		(fp_line
			(start -0.12065 -0.305054)
			(end -0.12065 -0.2794)
			(stroke
				(width 0.1)
				(type default)
			)
			(layer "F.Fab")
		)
		(fp_line
			(start -0.67945 0.3048)
			(end -0.67945 -0.305054)
			(stroke
				(width 0.1)
				(type default)
			)
			(layer "F.Fab")
		)
		(fp_line
			(start -0.67945 -0.305054)
			(end -0.12065 -0.305054)
			(stroke
				(width 0.1)
				(type default)
			)
			(layer "F.Fab")
		)
		(pad "1" smd circle
			(at -0.40005 0 180)
			(size 0 0)
			(layers "F.Cu" "F.Mask" "F.Paste")
			(net "NCSI_NIC2_RXD1")
		)
		(pad "2" smd circle
			(at 0.40005 0 180)
			(size 0 0)
			(layers "F.Cu" "F.Mask" "F.Paste")
			(net "GND")
		)
	)
	(footprint ""
		(layer "F.Cu")
		(at 194.164712 -343.952322 90)
		(property "Reference" "C373"
			(at 0 0 90)
			(layer "F.SilkS")
			(hide yes)
			(effects
				(font
					(size 1.27 1.27)
				)
			)
		)
		(property "Value" ""
			(at 0 0 90)
			(layer "F.Fab")
			(effects
				(font
					(size 1.27 1.27)
				)
			)
		)
		(duplicate_pad_numbers_are_jumpers no)
		(fp_line
			(start 0.299974 -0.150114)
			(end 0.299974 0.150114)
			(stroke
				(width 0.1)
				(type default)
			)
			(layer "F.Fab")
		)
		(fp_line
			(start -0.299974 -0.150114)
			(end 0.299974 -0.150114)
			(stroke
				(width 0.1)
				(type default)
			)
			(layer "F.Fab")
		)
		(fp_line
			(start 0.299974 0.150114)
			(end -0.299974 0.150114)
			(stroke
				(width 0.1)
				(type default)
			)
			(layer "F.Fab")
		)
		(fp_line
			(start -0.299974 0.150114)
			(end -0.299974 -0.150114)
			(stroke
				(width 0.1)
				(type default)
			)
			(layer "F.Fab")
		)
		(pad "1" smd rect
			(at -0.2667 0 90)
			(size 0.3048 0.381)
			(layers "F.Cu" "F.Mask" "F.Paste")
			(net "P5E_PEX1_STN7_TX_DN<127>")
		)
		(pad "2" smd rect
			(at 0.2667 0 90)
			(size 0.3048 0.381)
			(layers "F.Cu" "F.Mask" "F.Paste")
			(net "P5E_PEX1_STN7_TX_C_DN<127>")
		)
	)
	(footprint ""
		(layer "F.Cu")
		(at 217.235786 -213.222586 180)
		(property "Reference" "R5773"
			(at 0 0 180)
			(layer "F.SilkS")
			(hide yes)
			(effects
				(font
					(size 1.27 1.27)
				)
			)
		)
		(property "Value" ""
			(at 0 0 180)
			(layer "F.Fab")
			(effects
				(font
					(size 1.27 1.27)
				)
			)
		)
		(duplicate_pad_numbers_are_jumpers no)
		(fp_line
			(start 0.7874 0.4064)
			(end -0.7874 0.4064)
			(stroke
				(width 0.1524)
				(type default)
			)
			(layer "F.SilkS")
		)
		(fp_line
			(start 0.7874 -0.4064)
			(end 0.7874 0.4064)
			(stroke
				(width 0.1524)
				(type default)
			)
			(layer "F.SilkS")
		)
		(fp_line
			(start -0.7874 0.4064)
			(end -0.7874 -0.4064)
			(stroke
				(width 0.1524)
				(type default)
			)
			(layer "F.SilkS")
		)
		(fp_line
			(start -0.7874 -0.4064)
			(end 0.7874 -0.4064)
			(stroke
				(width 0.1524)
				(type default)
			)
			(layer "F.SilkS")
		)
		(fp_line
			(start 0.67945 0.3048)
			(end 0.120396 0.3048)
			(stroke
				(width 0.1)
				(type default)
			)
			(layer "F.Fab")
		)
		(fp_line
			(start 0.67945 -0.3048)
			(end 0.67945 0.3048)
			(stroke
				(width 0.1)
				(type default)
			)
			(layer "F.Fab")
		)
		(fp_line
			(start 0.12065 -0.2794)
			(end 0.12065 -0.3048)
			(stroke
				(width 0.1)
				(type default)
			)
			(layer "F.Fab")
		)
		(fp_line
			(start 0.12065 -0.3048)
			(end 0.67945 -0.3048)
			(stroke
				(width 0.1)
				(type default)
			)
			(layer "F.Fab")
		)
		(fp_line
			(start 0.120396 0.3048)
			(end 0.120396 0.2794)
			(stroke
				(width 0.1)
				(type default)
			)
			(layer "F.Fab")
		)
		(fp_line
			(start 0.120396 0.2794)
			(end -0.12065 0.2794)
			(stroke
				(width 0.1)
				(type default)
			)
			(layer "F.Fab")
		)
		(fp_line
			(start -0.12065 0.3048)
			(end -0.67945 0.3048)
			(stroke
				(width 0.1)
				(type default)
			)
			(layer "F.Fab")
		)
		(fp_line
			(start -0.12065 0.2794)
			(end -0.12065 0.3048)
			(stroke
				(width 0.1)
				(type default)
			)
			(layer "F.Fab")
		)
		(fp_line
			(start -0.12065 -0.2794)
			(end 0.12065 -0.2794)
			(stroke
				(width 0.1)
				(type default)
			)
			(layer "F.Fab")
		)
		(fp_line
			(start -0.12065 -0.305054)
			(end -0.12065 -0.2794)
			(stroke
				(width 0.1)
				(type default)
			)
			(layer "F.Fab")
		)
		(fp_line
			(start -0.67945 0.3048)
			(end -0.67945 -0.305054)
			(stroke
				(width 0.1)
				(type default)
			)
			(layer "F.Fab")
		)
		(fp_line
			(start -0.67945 -0.305054)
			(end -0.12065 -0.305054)
			(stroke
				(width 0.1)
				(type default)
			)
			(layer "F.Fab")
		)
		(pad "1" smd circle
			(at -0.40005 0 180)
			(size 0 0)
			(layers "F.Cu" "F.Mask" "F.Paste")
			(net "SMB_ALERT_PMBUS_R_N")
		)
		(pad "2" smd circle
			(at 0.40005 0 180)
			(size 0 0)
			(layers "F.Cu" "F.Mask" "F.Paste")
			(net "P0V8_PEX2_SMBALERT")
		)
	)
	(footprint ""
		(layer "F.Cu")
		(at 145.988278 -257.64871 -90)
		(property "Reference" "C3227"
			(at 0 0 270)
			(layer "F.SilkS")
			(hide yes)
			(effects
				(font
					(size 1.27 1.27)
				)
			)
		)
		(property "Value" ""
			(at 0 0 270)
			(layer "F.Fab")
			(effects
				(font
					(size 1.27 1.27)
				)
			)
		)
		(duplicate_pad_numbers_are_jumpers no)
		(fp_line
			(start -1.2954 0.5842)
			(end -1.2954 -0.5842)
			(stroke
				(width 0.1524)
				(type default)
			)
			(layer "F.SilkS")
		)
		(fp_line
			(start 1.2954 0.5842)
			(end -1.2954 0.5842)
			(stroke
				(width 0.1524)
				(type default)
			)
			(layer "F.SilkS")
		)
		(fp_line
			(start -1.2954 -0.5842)
			(end 1.2954 -0.5842)
			(stroke
				(width 0.1524)
				(type default)
			)
			(layer "F.SilkS")
		)
		(fp_line
			(start 1.2954 -0.5842)
			(end 1.2954 0.5842)
			(stroke
				(width 0.1524)
				(type default)
			)
			(layer "F.SilkS")
		)
		(fp_line
			(start -0.8636 0.4572)
			(end -0.8636 0.4064)
			(stroke
				(width 0.1)
				(type default)
			)
			(layer "F.Fab")
		)
		(fp_line
			(start 0.8636 0.4572)
			(end -0.8636 0.4572)
			(stroke
				(width 0.1)
				(type default)
			)
			(layer "F.Fab")
		)
		(fp_line
			(start -1.1938 0.4064)
			(end -1.1938 -0.4064)
			(stroke
				(width 0.1)
				(type default)
			)
			(layer "F.Fab")
		)
		(fp_line
			(start -0.8636 0.4064)
			(end -1.1938 0.4064)
			(stroke
				(width 0.1)
				(type default)
			)
			(layer "F.Fab")
		)
		(fp_line
			(start 0.8636 0.4064)
			(end 0.8636 0.4572)
			(stroke
				(width 0.1)
				(type default)
			)
			(layer "F.Fab")
		)
		(fp_line
			(start 1.1938 0.4064)
			(end 0.8636 0.4064)
			(stroke
				(width 0.1)
				(type default)
			)
			(layer "F.Fab")
		)
		(fp_line
			(start -1.1938 -0.4064)
			(end -0.8636 -0.4064)
			(stroke
				(width 0.1)
				(type default)
			)
			(layer "F.Fab")
		)
		(fp_line
			(start -0.8636 -0.4064)
			(end -0.8636 -0.4572)
			(stroke
				(width 0.1)
				(type default)
			)
			(layer "F.Fab")
		)
		(fp_line
			(start 0.8636 -0.4064)
			(end 1.1938 -0.4064)
			(stroke
				(width 0.1)
				(type default)
			)
			(layer "F.Fab")
		)
		(fp_line
			(start 1.1938 -0.4064)
			(end 1.1938 0.4064)
			(stroke
				(width 0.1)
				(type default)
			)
			(layer "F.Fab")
		)
		(fp_line
			(start -0.8636 -0.4572)
			(end 0.8636 -0.4572)
			(stroke
				(width 0.1)
				(type default)
			)
			(layer "F.Fab")
		)
		(fp_line
			(start 0.8636 -0.4572)
			(end 0.8636 -0.4064)
			(stroke
				(width 0.1)
				(type default)
			)
			(layer "F.Fab")
		)
		(pad "1" smd rect
			(at -0.7366 0 180)
			(size 0.7112 0.8128)
			(layers "F.Cu" "F.Mask" "F.Paste")
			(net "P1V8_PLL0_PEX1")
		)
		(pad "2" smd rect
			(at 0.7366 0 180)
			(size 0.7112 0.8128)
			(layers "F.Cu" "F.Mask" "F.Paste")
			(net "GND")
		)
	)
	(footprint ""
		(layer "F.Cu")
		(at 198.76135 -145.311114 180)
		(property "Reference" "C224"
			(at 0 0 180)
			(layer "F.SilkS")
			(hide yes)
			(effects
				(font
					(size 1.27 1.27)
				)
			)
		)
		(property "Value" ""
			(at 0 0 180)
			(layer "F.Fab")
			(effects
				(font
					(size 1.27 1.27)
				)
			)
		)
		(duplicate_pad_numbers_are_jumpers no)
		(fp_line
			(start 0.299974 0.150114)
			(end -0.299974 0.150114)
			(stroke
				(width 0.1)
				(type default)
			)
			(layer "F.Fab")
		)
		(fp_line
			(start 0.299974 -0.150114)
			(end 0.299974 0.150114)
			(stroke
				(width 0.1)
				(type default)
			)
			(layer "F.Fab")
		)
		(fp_line
			(start -0.299974 0.150114)
			(end -0.299974 -0.150114)
			(stroke
				(width 0.1)
				(type default)
			)
			(layer "F.Fab")
		)
		(fp_line
			(start -0.299974 -0.150114)
			(end 0.299974 -0.150114)
			(stroke
				(width 0.1)
				(type default)
			)
			(layer "F.Fab")
		)
		(pad "1" smd rect
			(at -0.2667 0 180)
			(size 0.3048 0.381)
			(layers "F.Cu" "F.Mask" "F.Paste")
			(net "P5E_PEX1_STN0_TX_DP<9>")
		)
		(pad "2" smd rect
			(at 0.2667 0 180)
			(size 0.3048 0.381)
			(layers "F.Cu" "F.Mask" "F.Paste")
			(net "P5E_PEX1_STN0_TX_C_DP<9>")
		)
	)
	(footprint ""
		(layer "F.Cu")
		(at 446.959482 -61.612526)
		(property "Reference" "PD40"
			(at -3.7084 -2.733548 0)
			(unlocked yes)
			(layer "F.SilkS")
			(effects
				(font
					(size 0.7874 0.5842)
					(thickness 0.1524)
				)
				(justify left)
			)
		)
		(property "Value" ""
			(at 0 0 0)
			(layer "F.Fab")
			(effects
				(font
					(size 1.27 1.27)
				)
			)
		)
		(duplicate_pad_numbers_are_jumpers no)
		(fp_line
			(start -3.656584 -1.970024)
			(end -3.656584 1.970024)
			(stroke
				(width 0.1524)
				(type default)
			)
			(layer "F.SilkS")
		)
		(fp_line
			(start -3.656584 1.970024)
			(end 4.240784 1.970024)
			(stroke
				(width 0.1524)
				(type default)
			)
			(layer "F.SilkS")
		)
		(fp_line
			(start 4.240784 -1.970024)
			(end -3.656584 -1.970024)
			(stroke
				(width 0.1524)
				(type default)
			)
			(layer "F.SilkS")
		)
		(fp_line
			(start 4.240784 1.970024)
			(end 4.240784 -1.970024)
			(stroke
				(width 0.1524)
				(type default)
			)
			(layer "F.SilkS")
		)
		(fp_poly
			(pts
				(xy 3.580384 1.970024) (xy 3.580384 -1.970024) (xy 4.240784 -1.970024) (xy 4.240784 1.970024)
			)
			(stroke
				(width 0)
				(type default)
			)
			(fill yes)
			(layer "F.SilkS")
		)
		(fp_line
			(start -2.3749 -1.970024)
			(end -2.3749 1.970024)
			(stroke
				(width 0.1)
				(type default)
			)
			(layer "F.Fab")
		)
		(fp_line
			(start -2.3749 1.970024)
			(end 2.3749 1.970024)
			(stroke
				(width 0.1)
				(type default)
			)
			(layer "F.Fab")
		)
		(fp_line
			(start 2.3749 -1.970024)
			(end -2.3749 -1.970024)
			(stroke
				(width 0.1)
				(type default)
			)
			(layer "F.Fab")
		)
		(fp_line
			(start 2.3749 1.970024)
			(end 2.3749 -1.970024)
			(stroke
				(width 0.1)
				(type default)
			)
			(layer "F.Fab")
		)
		(fp_text user "+"
			(at -4.9784 -0.23495 0)
			(unlocked yes)
			(layer "F.Fab")
			(effects
				(font
					(size 1.905 1.4224)
					(thickness 0.1524)
				)
				(justify left)
			)
		)
		(fp_text user "-"
			(at 4.1656 -0.23495 0)
			(unlocked yes)
			(layer "F.Fab")
			(effects
				(font
					(size 1.905 1.4224)
					(thickness 0.1524)
				)
				(justify left)
			)
		)
		(pad "A" smd rect
			(at -2.450084 0)
			(size 2.159 2.2606)
			(layers "F.Cu" "F.Mask" "F.Paste")
			(net "GND")
		)
		(pad "C" smd rect
			(at 2.450084 0)
			(size 2.159 2.2606)
			(layers "F.Cu" "F.Mask" "F.Paste")
			(net "P12V_AUX")
		)
	)
)
